# S9S_MB_2U (Grand Teton) — schematic netlist excerpt (pin names and nets, part order shuffled) for the footprints in the layout excerpt that follows; sources: Cadence DE-HDL packaged netlist, KiCad conversion of 03242023_DA0F0TMBIJ0_F0T_Motherboard_J_brd_V01_OCP.brd

R766  Q_RES  1K 1% EMPTY  pkg 0402LF  page 131 : A = P3V3_AUX ; B = JTAG_DBP_POWER_BTN_N
R1262  Q_RES  10K 1% EMPTY  pkg 0402LF  page 204 : A = P1V05_PCH_AUX ; B = H_CPU_ERR2_PCH_R_N

(kicad_pcb
	(version 20260206)
	(generator "pcbnew")
	(generator_version "10.0")
	(general
		(thickness 1.6)
		(legacy_teardrops no)
	)
	(paper "A4")
	(title_block
		(title "03242023_DA0F0TMBIJ0_F0T_Motherboard_J_brd_V01_OCP.brd")
		(comment 1 "Grand Teton / footprints 5809-5810 of 6105")
	)
	(layers
		(0 "F.Cu" signal "TOP")
		(4 "In1.Cu" signal "GND")
		(6 "In2.Cu" signal "IN1")
		(8 "In3.Cu" signal "GND1")
		(10 "In4.Cu" signal "IN2")
		(12 "In5.Cu" signal "GND2")
		(14 "In6.Cu" signal "IN3")
		(16 "In7.Cu" signal "GND3")
		(18 "In8.Cu" signal "VCC")
		(20 "In9.Cu" signal "VCC1")
		(22 "In10.Cu" signal "GND4")
		(24 "In11.Cu" signal "IN4")
		(26 "In12.Cu" signal "GND5")
		(28 "In13.Cu" signal "IN5")
		(30 "In14.Cu" signal "GND6")
		(32 "In15.Cu" signal "IN6")
		(34 "In16.Cu" signal "GND7")
		(2 "B.Cu" signal "BOTTOM")
		(9 "F.Adhes" user "F.Adhesive")
		(11 "B.Adhes" user "B.Adhesive")
		(13 "F.Paste" user "Package Geometry/Pastemask Top")
		(15 "B.Paste" user "Package Geometry/Pastemask Bottom")
		(5 "F.SilkS" user "Ref Des/Silkscreen Top")
		(7 "B.SilkS" user "Ref Des/Silkscreen Bottom")
		(1 "F.Mask" user "Board Geometry/Soldermask Top")
		(3 "B.Mask" user "Board Geometry/Soldermask Bottom")
		(17 "Dwgs.User" user "User.Drawings")
		(19 "Cmts.User" user "User.Comments")
		(21 "Eco1.User" user "User.Eco1")
		(23 "Eco2.User" user "User.Eco2")
		(25 "Edge.Cuts" user "Board Geometry/Outline")
		(27 "Margin" user)
		(31 "F.CrtYd" user "Package Geometry/Place Bound Top")
		(29 "B.CrtYd" user "Package Geometry/Place Bound Bottom")
		(35 "F.Fab" user "Ref Des/Assembly Top")
		(33 "B.Fab" user "Ref Des/Assembly Bottom")
	)
	(footprint ""
		(layer "B.Cu")
		(at 315.14288 -49.113948 180)
		(property "Reference" "R1262"
			(at 0 0 0)
			(layer "B.SilkS")
			(hide yes)
			(effects
				(font
					(size 1.27 1.27)
				)
				(justify mirror)
			)
		)
		(property "Value" ""
			(at 0 0 0)
			(layer "B.Fab")
			(effects
				(font
					(size 1.27 1.27)
				)
				(justify mirror)
			)
		)
		(duplicate_pad_numbers_are_jumpers no)
		(fp_line
			(start 0.7874 0.4064)
			(end 0.7874 -0.4064)
			(stroke
				(width 0.1524)
				(type default)
			)
			(layer "B.SilkS")
		)
		(fp_line
			(start 0.7874 -0.4064)
			(end -0.7874 -0.4064)
			(stroke
				(width 0.1524)
				(type default)
			)
			(layer "B.SilkS")
		)
		(fp_line
			(start -0.7874 0.4064)
			(end 0.7874 0.4064)
			(stroke
				(width 0.1524)
				(type default)
			)
			(layer "B.SilkS")
		)
		(fp_line
			(start -0.7874 -0.4064)
			(end -0.7874 0.4064)
			(stroke
				(width 0.1524)
				(type default)
			)
			(layer "B.SilkS")
		)
		(fp_line
			(start 0.67945 0.3048)
			(end 0.67945 -0.305054)
			(stroke
				(width 0.1)
				(type default)
			)
			(layer "B.Fab")
		)
		(fp_line
			(start 0.67945 -0.305054)
			(end 0.12065 -0.305054)
			(stroke
				(width 0.1)
				(type default)
			)
			(layer "B.Fab")
		)
		(fp_line
			(start 0.12065 0.3048)
			(end 0.67945 0.3048)
			(stroke
				(width 0.1)
				(type default)
			)
			(layer "B.Fab")
		)
		(fp_line
			(start 0.12065 0.2794)
			(end 0.12065 0.3048)
			(stroke
				(width 0.1)
				(type default)
			)
			(layer "B.Fab")
		)
		(fp_line
			(start 0.12065 -0.2794)
			(end -0.12065 -0.2794)
			(stroke
				(width 0.1)
				(type default)
			)
			(layer "B.Fab")
		)
		(fp_line
			(start 0.12065 -0.305054)
			(end 0.12065 -0.2794)
			(stroke
				(width 0.1)
				(type default)
			)
			(layer "B.Fab")
		)
		(fp_line
			(start -0.120396 0.3048)
			(end -0.120396 0.2794)
			(stroke
				(width 0.1)
				(type default)
			)
			(layer "B.Fab")
		)
		(fp_line
			(start -0.120396 0.2794)
			(end 0.12065 0.2794)
			(stroke
				(width 0.1)
				(type default)
			)
			(layer "B.Fab")
		)
		(fp_line
			(start -0.12065 -0.2794)
			(end -0.12065 -0.3048)
			(stroke
				(width 0.1)
				(type default)
			)
			(layer "B.Fab")
		)
		(fp_line
			(start -0.12065 -0.3048)
			(end -0.67945 -0.3048)
			(stroke
				(width 0.1)
				(type default)
			)
			(layer "B.Fab")
		)
		(fp_line
			(start -0.67945 0.3048)
			(end -0.120396 0.3048)
			(stroke
				(width 0.1)
				(type default)
			)
			(layer "B.Fab")
		)
		(fp_line
			(start -0.67945 -0.3048)
			(end -0.67945 0.3048)
			(stroke
				(width 0.1)
				(type default)
			)
			(layer "B.Fab")
		)
		(pad "1" smd circle
			(at 0.40005 0)
			(size 0 0)
			(layers "B.Cu" "B.Mask" "B.Paste")
			(net "P1V05_PCH_AUX")
		)
		(pad "2" smd circle
			(at -0.40005 0)
			(size 0 0)
			(layers "B.Cu" "B.Mask" "B.Paste")
			(net "H_CPU_ERR2_PCH_R_N")
		)
	)
	(footprint ""
		(layer "B.Cu")
		(at 404.006812 -53.727604)
		(property "Reference" "R766"
			(at 0 0 0)
			(layer "B.SilkS")
			(hide yes)
			(effects
				(font
					(size 1.27 1.27)
				)
				(justify mirror)
			)
		)
		(property "Value" ""
			(at 0 0 0)
			(layer "B.Fab")
			(effects
				(font
					(size 1.27 1.27)
				)
				(justify mirror)
			)
		)
		(duplicate_pad_numbers_are_jumpers no)
		(fp_line
			(start -0.7874 -0.4064)
			(end -0.7874 0.4064)
			(stroke
				(width 0.1524)
				(type default)
			)
			(layer "B.SilkS")
		)
		(fp_line
			(start -0.7874 0.4064)
			(end 0.7874 0.4064)
			(stroke
				(width 0.1524)
				(type default)
			)
			(layer "B.SilkS")
		)
		(fp_line
			(start 0.7874 -0.4064)
			(end -0.7874 -0.4064)
			(stroke
				(width 0.1524)
				(type default)
			)
			(layer "B.SilkS")
		)
		(fp_line
			(start 0.7874 0.4064)
			(end 0.7874 -0.4064)
			(stroke
				(width 0.1524)
				(type default)
			)
			(layer "B.SilkS")
		)
		(fp_line
			(start -0.67945 -0.3048)
			(end -0.67945 0.3048)
			(stroke
				(width 0.1)
				(type default)
			)
			(layer "B.Fab")
		)
		(fp_line
			(start -0.67945 0.3048)
			(end -0.120396 0.3048)
			(stroke
				(width 0.1)
				(type default)
			)
			(layer "B.Fab")
		)
		(fp_line
			(start -0.12065 -0.3048)
			(end -0.67945 -0.3048)
			(stroke
				(width 0.1)
				(type default)
			)
			(layer "B.Fab")
		)
		(fp_line
			(start -0.12065 -0.2794)
			(end -0.12065 -0.3048)
			(stroke
				(width 0.1)
				(type default)
			)
			(layer "B.Fab")
		)
		(fp_line
			(start -0.120396 0.2794)
			(end 0.12065 0.2794)
			(stroke
				(width 0.1)
				(type default)
			)
			(layer "B.Fab")
		)
		(fp_line
			(start -0.120396 0.3048)
			(end -0.120396 0.2794)
			(stroke
				(width 0.1)
				(type default)
			)
			(layer "B.Fab")
		)
		(fp_line
			(start 0.12065 -0.305054)
			(end 0.12065 -0.2794)
			(stroke
				(width 0.1)
				(type default)
			)
			(layer "B.Fab")
		)
		(fp_line
			(start 0.12065 -0.2794)
			(end -0.12065 -0.2794)
			(stroke
				(width 0.1)
				(type default)
			)
			(layer "B.Fab")
		)
		(fp_line
			(start 0.12065 0.2794)
			(end 0.12065 0.3048)
			(stroke
				(width 0.1)
				(type default)
			)
			(layer "B.Fab")
		)
		(fp_line
			(start 0.12065 0.3048)
			(end 0.67945 0.3048)
			(stroke
				(width 0.1)
				(type default)
			)
			(layer "B.Fab")
		)
		(fp_line
			(start 0.67945 -0.305054)
			(end 0.12065 -0.305054)
			(stroke
				(width 0.1)
				(type default)
			)
			(layer "B.Fab")
		)
		(fp_line
			(start 0.67945 0.3048)
			(end 0.67945 -0.305054)
			(stroke
				(width 0.1)
				(type default)
			)
			(layer "B.Fab")
		)
		(pad "1" smd circle
			(at 0.40005 0 180)
			(size 0 0)
			(layers "B.Cu" "B.Mask" "B.Paste")
			(net "P3V3_AUX")
		)
		(pad "2" smd circle
			(at -0.40005 0 180)
			(size 0 0)
			(layers "B.Cu" "B.Mask" "B.Paste")
			(net "JTAG_DBP_POWER_BTN_N")
		)
	)
)
